# TIMECARD (Time Appliance Project (Time Card)) — schematic netlist excerpt (pin names and nets, part order shuffled) for the footprints in the layout excerpt that follows; sources: Cadence DE-HDL packaged netlist, KiCad conversion of R4006-B0001-02_R01.brd

R50  RESISTOR  0OHM -  pkg SMC_0603R_H024  page 32 : \1\ = XP5R0V_AGND ; \2\ = XP5R0V_FB_R_TO_AGND
R440  RESISTOR  10KOHM 1%  pkg SMC_0402R_H016  page 13 : \1\ = FPGA_IN_MAC_PPS_OUTP ; \2\ = SG

(kicad_pcb
	(version 20260206)
	(generator "pcbnew")
	(generator_version "10.0")
	(general
		(thickness 1.6)
		(legacy_teardrops no)
	)
	(paper "A4")
	(title_block
		(title "timecard-production-celestica-r4006 — R4006-B0001-02_R01.brd")
		(comment 1 "Time Appliance Project (Time Card) / footprints 841-842 of 1113")
	)
	(layers
		(0 "F.Cu" signal "TOP")
		(4 "In1.Cu" signal "L02_GND1")
		(6 "In2.Cu" signal "L03_SIG1")
		(8 "In3.Cu" signal "L04_GND2")
		(10 "In4.Cu" signal "L05_VCC1")
		(12 "In5.Cu" signal "L06_VCC2")
		(14 "In6.Cu" signal "L07_GND3")
		(16 "In7.Cu" signal "L08_SIG2")
		(18 "In8.Cu" signal "L09_GND4")
		(2 "B.Cu" signal "BOTTOM")
		(9 "F.Adhes" user "F.Adhesive")
		(11 "B.Adhes" user "B.Adhesive")
		(13 "F.Paste" user "Package Geometry/Pastemask Top")
		(15 "B.Paste" user "Package Geometry/Pastemask Bottom")
		(5 "F.SilkS" user "Ref Des/Silkscreen Top")
		(7 "B.SilkS" user "Ref Des/Silkscreen Bottom")
		(1 "F.Mask" user "Board Geometry/Soldermask Top")
		(3 "B.Mask" user "Board Geometry/Soldermask Bottom")
		(17 "Dwgs.User" user "User.Drawings")
		(19 "Cmts.User" user "User.Comments")
		(21 "Eco1.User" user "User.Eco1")
		(23 "Eco2.User" user "User.Eco2")
		(25 "Edge.Cuts" user "Board Geometry/Outline")
		(27 "Margin" user)
		(31 "F.CrtYd" user "Package Geometry/Place Bound Top")
		(29 "B.CrtYd" user "Package Geometry/Place Bound Bottom")
		(35 "F.Fab" user "Ref Des/Assembly Top")
		(33 "B.Fab" user "Ref Des/Assembly Bottom")
	)
	(footprint ""
		(layer "B.Cu")
		(at 36.703 -103.886 180)
		(property "Reference" "R50"
			(at 4.064 -0.16637 0)
			(unlocked yes)
			(layer "B.SilkS")
			(effects
				(font
					(size 0.7874 0.5842)
					(thickness 0.1524)
				)
				(justify mirror)
			)
		)
		(property "Value" "VAL*"
			(at 0.0254 2.524506 180)
			(unlocked yes)
			(layer "B.Fab")
			(hide yes)
			(effects
				(font
					(size 0.7874 0.5842)
					(thickness 0.1524)
				)
				(justify mirror)
			)
		)
		(property "Device Type" "RESISTOR-G156-100R0-J0,0OHM,-"
			(at 0 1.610106 180)
			(unlocked yes)
			(layer "B.Fab")
			(hide yes)
			(effects
				(font
					(size 0.7874 0.5842)
					(thickness 0.1524)
				)
				(justify mirror)
			)
		)
		(property "User Part Number" "PARTNUM*"
			(at 0.0254 4.505706 180)
			(unlocked yes)
			(layer "Cmts.User")
			(hide yes)
			(effects
				(font
					(size 0.7874 0.5842)
					(thickness 0.1524)
				)
				(justify mirror)
			)
		)
		(property "Tolerance" "TOL*"
			(at 0.0254 3.464306 180)
			(unlocked yes)
			(layer "Cmts.User")
			(hide yes)
			(effects
				(font
					(size 0.7874 0.5842)
					(thickness 0.1524)
				)
				(justify mirror)
			)
		)
		(duplicate_pad_numbers_are_jumpers no)
		(fp_line
			(start 1.3208 0.7112)
			(end 1.3208 -0.7112)
			(stroke
				(width 0.1)
				(type default)
			)
			(layer "B.SilkS")
		)
		(fp_line
			(start 1.3208 -0.7112)
			(end -1.3208 -0.7112)
			(stroke
				(width 0.1)
				(type default)
			)
			(layer "B.SilkS")
		)
		(fp_line
			(start -1.3208 0.7112)
			(end 1.3208 0.7112)
			(stroke
				(width 0.1)
				(type default)
			)
			(layer "B.SilkS")
		)
		(fp_line
			(start -1.3208 -0.7112)
			(end -1.3208 0.7112)
			(stroke
				(width 0.1)
				(type default)
			)
			(layer "B.SilkS")
		)
		(fp_rect
			(start -1.3208 0.7112)
			(end 1.3208 -0.7112)
			(stroke
				(width 0)
				(type default)
			)
			(fill no)
			(layer "B.CrtYd")
		)
		(fp_line
			(start 0.8128 0.4572)
			(end 0.8128 -0.4572)
			(stroke
				(width 0.1)
				(type default)
			)
			(layer "B.Fab")
		)
		(fp_line
			(start 0.8128 -0.4572)
			(end -0.8128 -0.4572)
			(stroke
				(width 0.1)
				(type default)
			)
			(layer "B.Fab")
		)
		(fp_line
			(start -0.8128 0.4572)
			(end 0.8128 0.4572)
			(stroke
				(width 0.1)
				(type default)
			)
			(layer "B.Fab")
		)
		(fp_line
			(start -0.8128 -0.4572)
			(end -0.8128 0.4572)
			(stroke
				(width 0.1)
				(type default)
			)
			(layer "B.Fab")
		)
		(pad "1" smd rect
			(at 0.6858 0)
			(size 0.762 0.8636)
			(layers "B.Cu" "B.Mask" "B.Paste")
			(net "XP5R0V_AGND")
		)
		(pad "2" smd rect
			(at -0.6858 0)
			(size 0.762 0.8636)
			(layers "B.Cu" "B.Mask" "B.Paste")
			(net "XP5R0V_FB_R_TO_AGND")
		)
		(zone
			(layer "B.Cu")
			(hatch none 0.5)
			(connect_pads
				(clearance 0)
			)
			(min_thickness 0.25)
			(keepout
				(tracks allowed)
				(vias not_allowed)
				(pads allowed)
				(copperpour not_allowed)
				(footprints allowed)
			)
			(placement
				(enabled no)
				(sheetname "")
			)
			(fill
				(thermal_gap 0.5)
				(thermal_bridge_width 0.5)
				(island_removal_mode 0)
			)
			(polygon
				(pts
					(xy 36.8554 -104.3432) (xy 36.5506 -104.3432) (xy 36.5506 -103.4288) (xy 36.8554 -103.4288)
				)
			)
		)
	)
	(footprint ""
		(layer "B.Cu")
		(at 115.062 -29.464 90)
		(property "Reference" "R440"
			(at -3.556 0.08763 270)
			(unlocked yes)
			(layer "B.SilkS")
			(effects
				(font
					(size 0.7874 0.5842)
					(thickness 0.1524)
				)
				(justify mirror)
			)
		)
		(property "Value" "VAL*"
			(at -0.02032 2.13233 90)
			(unlocked yes)
			(layer "B.Fab")
			(hide yes)
			(effects
				(font
					(size 0.7874 0.5842)
					(thickness 0.1524)
				)
				(justify mirror)
			)
		)
		(property "Tolerance" "TOL*"
			(at -0.044704 3.05435 90)
			(unlocked yes)
			(layer "Cmts.User")
			(hide yes)
			(effects
				(font
					(size 0.7874 0.5842)
					(thickness 0.1524)
				)
				(justify mirror)
			)
		)
		(property "User Part Number" "PARTNUM*"
			(at -0.02032 4.024884 90)
			(unlocked yes)
			(layer "Cmts.User")
			(hide yes)
			(effects
				(font
					(size 0.7874 0.5842)
					(thickness 0.1524)
				)
				(justify mirror)
			)
		)
		(property "Device Type" "RESISTOR-G155-11002-01,10KOHM,A"
			(at -0.008382 1.210564 90)
			(unlocked yes)
			(layer "B.Fab")
			(hide yes)
			(effects
				(font
					(size 0.7874 0.5842)
					(thickness 0.1524)
				)
				(justify mirror)
			)
		)
		(duplicate_pad_numbers_are_jumpers no)
		(fp_line
			(start 1.143 -0.5588)
			(end 1.143 0.5588)
			(stroke
				(width 0.1)
				(type default)
			)
			(layer "B.SilkS")
		)
		(fp_line
			(start -1.143 -0.5588)
			(end 1.143 -0.5588)
			(stroke
				(width 0.1)
				(type default)
			)
			(layer "B.SilkS")
		)
		(fp_line
			(start 1.143 0.5588)
			(end -1.143 0.5588)
			(stroke
				(width 0.1)
				(type default)
			)
			(layer "B.SilkS")
		)
		(fp_line
			(start -1.143 0.5588)
			(end -1.143 -0.5588)
			(stroke
				(width 0.1)
				(type default)
			)
			(layer "B.SilkS")
		)
		(fp_poly
			(pts
				(xy 1.143 0.5588) (xy -1.143 0.5588) (xy -1.143 -0.5588) (xy 1.143 -0.5588)
			)
			(stroke
				(width 0)
				(type default)
			)
			(fill no)
			(layer "B.CrtYd")
		)
		(fp_line
			(start 0.508 -0.3048)
			(end 0.508 0.3048)
			(stroke
				(width 0.1)
				(type default)
			)
			(layer "B.Fab")
		)
		(fp_line
			(start -0.508 -0.3048)
			(end 0.508 -0.3048)
			(stroke
				(width 0.1)
				(type default)
			)
			(layer "B.Fab")
		)
		(fp_line
			(start 0.508 0.3048)
			(end -0.508 0.3048)
			(stroke
				(width 0.1)
				(type default)
			)
			(layer "B.Fab")
		)
		(fp_line
			(start -0.508 0.3048)
			(end -0.508 -0.3048)
			(stroke
				(width 0.1)
				(type default)
			)
			(layer "B.Fab")
		)
		(pad "1" smd rect
			(at 0.5334 0 270)
			(size 0.7112 0.6096)
			(layers "B.Cu" "B.Mask" "B.Paste")
			(net "FPGA_IN_MAC_PPS_OUTP")
		)
		(pad "2" smd rect
			(at -0.5334 0 270)
			(size 0.7112 0.6096)
			(layers "B.Cu" "B.Mask" "B.Paste")
			(net "SG")
		)
		(zone
			(layer "B.Cu")
			(hatch none 0.5)
			(connect_pads
				(clearance 0)
			)
			(min_thickness 0.25)
			(keepout
				(tracks not_allowed)
				(vias allowed)
				(pads allowed)
				(copperpour not_allowed)
				(footprints allowed)
			)
			(placement
				(enabled no)
				(sheetname "")
			)
			(fill
				(thermal_gap 0.5)
				(thermal_bridge_width 0.5)
				(island_removal_mode 0)
			)
			(polygon
				(pts
					(xy 115.3668 -29.5402) (xy 114.7572 -29.5402) (xy 114.7572 -29.3878) (xy 115.3668 -29.3878)
				)
			)
		)
		(zone
			(layer "B.Cu")
			(hatch none 0.5)
			(connect_pads
				(clearance 0)
			)
			(min_thickness 0.25)
			(keepout
				(tracks allowed)
				(vias not_allowed)
				(pads allowed)
				(copperpour not_allowed)
				(footprints allowed)
			)
			(placement
				(enabled no)
				(sheetname "")
			)
			(fill
				(thermal_gap 0.5)
				(thermal_bridge_width 0.5)
				(island_removal_mode 0)
			)
			(polygon
				(pts
					(xy 115.3668 -29.5402) (xy 114.7572 -29.5402) (xy 114.7572 -29.3878) (xy 115.3668 -29.3878)
				)
			)
		)
	)
)
